# T6G (Grand Teton) — schematic netlist excerpt (pin names and nets, part order shuffled) for the footprints in the layout excerpt that follows; sources: Cadence DE-HDL packaged netlist, KiCad conversion of 04192023_DAF0TMB3IC0_F0TG_MB_C_brd_V02_OCP.brd

PJ09_P1_N  Q_SHORT  EMPTY  pkg SM  page 364 : \1\ = GND ; \2\ = P0V9_RETIMER_CPU1_SENSE_SH_N
C10179  Q_CAP  22UF 4V 20% X6S  pkg C0402  page 69 : A = PVDDCR_CPU0_P0 ; B = GND
R114  Q_RES  1K 1% EMPTY  pkg 0402LF  page 108 : A = P3V3 ; B = PWRGD_CHK_CPU1_DIMM

(kicad_pcb
	(version 20260206)
	(generator "pcbnew")
	(generator_version "10.0")
	(general
		(thickness 1.6)
		(legacy_teardrops no)
	)
	(paper "A4")
	(title_block
		(title "04192023_DAF0TMB3IC0_F0TG_MB_C_brd_V02_OCP.brd")
		(comment 1 "Grand Teton / footprints 5700-5702 of 8354")
	)
	(layers
		(0 "F.Cu" signal "TOP")
		(4 "In1.Cu" signal "GND")
		(6 "In2.Cu" signal "IN1")
		(8 "In3.Cu" signal "GND1")
		(10 "In4.Cu" signal "IN2")
		(12 "In5.Cu" signal "GND2")
		(14 "In6.Cu" signal "IN3")
		(16 "In7.Cu" signal "GND3")
		(18 "In8.Cu" signal "VCC")
		(20 "In9.Cu" signal "VCC1")
		(22 "In10.Cu" signal "GND4")
		(24 "In11.Cu" signal "IN4")
		(26 "In12.Cu" signal "GND5")
		(28 "In13.Cu" signal "IN5")
		(30 "In14.Cu" signal "GND6")
		(32 "In15.Cu" signal "IN6")
		(34 "In16.Cu" signal "GND7")
		(2 "B.Cu" signal "BOTTOM")
		(9 "F.Adhes" user "F.Adhesive")
		(11 "B.Adhes" user "B.Adhesive")
		(13 "F.Paste" user "Package Geometry/Pastemask Top")
		(15 "B.Paste" user "Package Geometry/Pastemask Bottom")
		(5 "F.SilkS" user "Ref Des/Silkscreen Top")
		(7 "B.SilkS" user "Ref Des/Silkscreen Bottom")
		(1 "F.Mask" user "Board Geometry/Soldermask Top")
		(3 "B.Mask" user "Board Geometry/Soldermask Bottom")
		(17 "Dwgs.User" user "User.Drawings")
		(19 "Cmts.User" user "User.Comments")
		(21 "Eco1.User" user "User.Eco1")
		(23 "Eco2.User" user "User.Eco2")
		(25 "Edge.Cuts" user "Board Geometry/Outline")
		(27 "Margin" user)
		(31 "F.CrtYd" user "Package Geometry/Place Bound Top")
		(29 "B.CrtYd" user "Package Geometry/Place Bound Bottom")
		(35 "F.Fab" user "Ref Des/Assembly Top")
		(33 "B.Fab" user "Ref Des/Assembly Bottom")
	)
	(footprint ""
		(layer "B.Cu")
		(at 195.359782 -193.996564)
		(property "Reference" "R114"
			(at 0 0 0)
			(layer "B.SilkS")
			(hide yes)
			(effects
				(font
					(size 1.27 1.27)
				)
				(justify mirror)
			)
		)
		(property "Value" ""
			(at 0 0 0)
			(layer "B.Fab")
			(effects
				(font
					(size 1.27 1.27)
				)
				(justify mirror)
			)
		)
		(duplicate_pad_numbers_are_jumpers no)
		(fp_line
			(start -0.7874 -0.4064)
			(end -0.7874 0.4064)
			(stroke
				(width 0.1524)
				(type default)
			)
			(layer "B.SilkS")
		)
		(fp_line
			(start -0.7874 0.4064)
			(end 0.7874 0.4064)
			(stroke
				(width 0.1524)
				(type default)
			)
			(layer "B.SilkS")
		)
		(fp_line
			(start 0.7874 -0.4064)
			(end -0.7874 -0.4064)
			(stroke
				(width 0.1524)
				(type default)
			)
			(layer "B.SilkS")
		)
		(fp_line
			(start 0.7874 0.4064)
			(end 0.7874 -0.4064)
			(stroke
				(width 0.1524)
				(type default)
			)
			(layer "B.SilkS")
		)
		(fp_line
			(start -0.67945 -0.3048)
			(end -0.67945 0.3048)
			(stroke
				(width 0.1)
				(type default)
			)
			(layer "B.Fab")
		)
		(fp_line
			(start -0.67945 0.3048)
			(end -0.120396 0.3048)
			(stroke
				(width 0.1)
				(type default)
			)
			(layer "B.Fab")
		)
		(fp_line
			(start -0.12065 -0.3048)
			(end -0.67945 -0.3048)
			(stroke
				(width 0.1)
				(type default)
			)
			(layer "B.Fab")
		)
		(fp_line
			(start -0.12065 -0.2794)
			(end -0.12065 -0.3048)
			(stroke
				(width 0.1)
				(type default)
			)
			(layer "B.Fab")
		)
		(fp_line
			(start -0.120396 0.2794)
			(end 0.12065 0.2794)
			(stroke
				(width 0.1)
				(type default)
			)
			(layer "B.Fab")
		)
		(fp_line
			(start -0.120396 0.3048)
			(end -0.120396 0.2794)
			(stroke
				(width 0.1)
				(type default)
			)
			(layer "B.Fab")
		)
		(fp_line
			(start 0.12065 -0.305054)
			(end 0.12065 -0.2794)
			(stroke
				(width 0.1)
				(type default)
			)
			(layer "B.Fab")
		)
		(fp_line
			(start 0.12065 -0.2794)
			(end -0.12065 -0.2794)
			(stroke
				(width 0.1)
				(type default)
			)
			(layer "B.Fab")
		)
		(fp_line
			(start 0.12065 0.2794)
			(end 0.12065 0.3048)
			(stroke
				(width 0.1)
				(type default)
			)
			(layer "B.Fab")
		)
		(fp_line
			(start 0.12065 0.3048)
			(end 0.67945 0.3048)
			(stroke
				(width 0.1)
				(type default)
			)
			(layer "B.Fab")
		)
		(fp_line
			(start 0.67945 -0.305054)
			(end 0.12065 -0.305054)
			(stroke
				(width 0.1)
				(type default)
			)
			(layer "B.Fab")
		)
		(fp_line
			(start 0.67945 0.3048)
			(end 0.67945 -0.305054)
			(stroke
				(width 0.1)
				(type default)
			)
			(layer "B.Fab")
		)
		(pad "1" smd circle
			(at 0.40005 0 180)
			(size 0 0)
			(layers "B.Cu" "B.Mask" "B.Paste")
			(net "P3V3")
		)
		(pad "2" smd circle
			(at -0.40005 0 180)
			(size 0 0)
			(layers "B.Cu" "B.Mask" "B.Paste")
			(net "PWRGD_CHK_CPU1_DIMM")
		)
	)
	(footprint ""
		(layer "B.Cu")
		(at 365.836454 -249.36831)
		(property "Reference" "C10179"
			(at 0 0 0)
			(layer "B.SilkS")
			(hide yes)
			(effects
				(font
					(size 1.27 1.27)
				)
				(justify mirror)
			)
		)
		(property "Value" ""
			(at 0 0 0)
			(layer "B.Fab")
			(effects
				(font
					(size 1.27 1.27)
				)
				(justify mirror)
			)
		)
		(duplicate_pad_numbers_are_jumpers no)
		(fp_line
			(start -0.7874 -0.4064)
			(end -0.7874 0.4064)
			(stroke
				(width 0.1524)
				(type default)
			)
			(layer "B.SilkS")
		)
		(fp_line
			(start -0.7874 0.4064)
			(end 0.7874 0.4064)
			(stroke
				(width 0.1524)
				(type default)
			)
			(layer "B.SilkS")
		)
		(fp_line
			(start 0.7874 -0.4064)
			(end -0.7874 -0.4064)
			(stroke
				(width 0.1524)
				(type default)
			)
			(layer "B.SilkS")
		)
		(fp_line
			(start 0.7874 0.4064)
			(end 0.7874 -0.4064)
			(stroke
				(width 0.1524)
				(type default)
			)
			(layer "B.SilkS")
		)
		(fp_line
			(start -0.67945 -0.3048)
			(end -0.67945 0.3048)
			(stroke
				(width 0.1)
				(type default)
			)
			(layer "B.Fab")
		)
		(fp_line
			(start -0.67945 0.3048)
			(end -0.120396 0.3048)
			(stroke
				(width 0.1)
				(type default)
			)
			(layer "B.Fab")
		)
		(fp_line
			(start -0.12065 -0.3048)
			(end -0.67945 -0.3048)
			(stroke
				(width 0.1)
				(type default)
			)
			(layer "B.Fab")
		)
		(fp_line
			(start -0.12065 -0.2794)
			(end -0.12065 -0.3048)
			(stroke
				(width 0.1)
				(type default)
			)
			(layer "B.Fab")
		)
		(fp_line
			(start -0.120396 0.2794)
			(end 0.12065 0.2794)
			(stroke
				(width 0.1)
				(type default)
			)
			(layer "B.Fab")
		)
		(fp_line
			(start -0.120396 0.3048)
			(end -0.120396 0.2794)
			(stroke
				(width 0.1)
				(type default)
			)
			(layer "B.Fab")
		)
		(fp_line
			(start 0.12065 -0.305054)
			(end 0.12065 -0.2794)
			(stroke
				(width 0.1)
				(type default)
			)
			(layer "B.Fab")
		)
		(fp_line
			(start 0.12065 -0.2794)
			(end -0.12065 -0.2794)
			(stroke
				(width 0.1)
				(type default)
			)
			(layer "B.Fab")
		)
		(fp_line
			(start 0.12065 0.2794)
			(end 0.12065 0.3048)
			(stroke
				(width 0.1)
				(type default)
			)
			(layer "B.Fab")
		)
		(fp_line
			(start 0.12065 0.3048)
			(end 0.67945 0.3048)
			(stroke
				(width 0.1)
				(type default)
			)
			(layer "B.Fab")
		)
		(fp_line
			(start 0.67945 -0.305054)
			(end 0.12065 -0.305054)
			(stroke
				(width 0.1)
				(type default)
			)
			(layer "B.Fab")
		)
		(fp_line
			(start 0.67945 0.3048)
			(end 0.67945 -0.305054)
			(stroke
				(width 0.1)
				(type default)
			)
			(layer "B.Fab")
		)
		(pad "1" smd circle
			(at 0.40005 0 180)
			(size 0 0)
			(layers "B.Cu" "B.Mask" "B.Paste")
			(net "PVDDCR_CPU0_P0")
		)
		(pad "2" smd circle
			(at -0.40005 0 180)
			(size 0 0)
			(layers "B.Cu" "B.Mask" "B.Paste")
			(net "GND")
		)
	)
	(footprint ""
		(layer "B.Cu")
		(at 138.24204 -389.43026)
		(property "Reference" "PJ09_P1_N"
			(at 0 0 0)
			(layer "B.SilkS")
			(hide yes)
			(effects
				(font
					(size 1.27 1.27)
				)
				(justify mirror)
			)
		)
		(property "Value" ""
			(at 0 0 0)
			(layer "B.Fab")
			(effects
				(font
					(size 1.27 1.27)
				)
				(justify mirror)
			)
		)
		(duplicate_pad_numbers_are_jumpers no)
		(zone
			(layer "In15.Cu")
			(hatch none 0.5)
			(connect_pads
				(clearance 0)
			)
			(min_thickness 0.25)
			(keepout
				(tracks allowed)
				(vias not_allowed)
				(pads allowed)
				(copperpour not_allowed)
				(footprints allowed)
			)
			(placement
				(enabled no)
				(sheetname "")
			)
			(fill
				(thermal_gap 0.5)
				(thermal_bridge_width 0.5)
				(island_removal_mode 0)
			)
			(polygon
				(pts
					(xy 138.45794 -389.23976) (xy 138.02614 -389.23976) (xy 138.02614 -389.62076) (xy 138.45794 -389.62076)
				)
			)
		)
	)
)
